# BASEBOARD_FAB2 (Tioga Pass) — schematic netlist excerpt (pin names and nets, part order shuffled) for the footprints in the layout excerpt that follows; sources: Cadence DE-HDL packaged netlist, KiCad conversion of Wiwynn_Tioga_Pass_MB.brd

R778  RES  0.0 5% CHIP  pkg 0402  page 244 : A = P3E_CPU0_PE1_PCH_RXN<11> ; B = P3E_CPU0_PE1_PCH_CON_RXN<11>
R1T8  RES  20.0 1% CHIP  pkg 0402  page 160 : A = SMB_SLOTX24_STBY_LVC3_SDA_R ; B = SMB_SLOTX24_BMC_STBY_LVC3_SDA
C7C19  CAP_A  1.0UF 6.3V 10% X6S  pkg 0402V  page 137 : A = RST_RTCRST_N ; B = GND

(kicad_pcb
	(version 20260206)
	(generator "pcbnew")
	(generator_version "10.0")
	(general
		(thickness 1.6)
		(legacy_teardrops no)
	)
	(paper "A4")
	(title_block
		(title "Wiwynn_Tioga_Pass_MB.brd")
		(comment 1 "Tioga Pass / footprints 4616-4618 of 4770")
	)
	(layers
		(0 "F.Cu" signal "TOP")
		(4 "In1.Cu" signal "L2GND")
		(6 "In2.Cu" signal "L3")
		(8 "In3.Cu" signal "L4GND")
		(10 "In4.Cu" signal "L5")
		(12 "In5.Cu" signal "L6GND")
		(14 "In6.Cu" signal "L7VCC")
		(16 "In7.Cu" signal "L8VCC")
		(18 "In8.Cu" signal "L9GND")
		(20 "In9.Cu" signal "L10")
		(22 "In10.Cu" signal "L11GND")
		(24 "In11.Cu" signal "L12")
		(26 "In12.Cu" signal "L13GND")
		(2 "B.Cu" signal "BOTTOM")
		(9 "F.Adhes" user "F.Adhesive")
		(11 "B.Adhes" user "B.Adhesive")
		(13 "F.Paste" user "Package Geometry/Pastemask Top")
		(15 "B.Paste" user "Package Geometry/Pastemask Bottom")
		(5 "F.SilkS" user "Ref Des/Silkscreen Top")
		(7 "B.SilkS" user "Ref Des/Silkscreen Bottom")
		(1 "F.Mask" user "Board Geometry/Soldermask Top")
		(3 "B.Mask" user "Board Geometry/Soldermask Bottom")
		(17 "Dwgs.User" user "User.Drawings")
		(19 "Cmts.User" user "User.Comments")
		(21 "Eco1.User" user "User.Eco1")
		(23 "Eco2.User" user "User.Eco2")
		(25 "Edge.Cuts" user "Board Geometry/Outline")
		(27 "Margin" user)
		(31 "F.CrtYd" user "Package Geometry/Place Bound Top")
		(29 "B.CrtYd" user "Package Geometry/Place Bound Bottom")
		(35 "F.Fab" user "Ref Des/Assembly Top")
		(33 "B.Fab" user "Ref Des/Assembly Bottom")
	)
	(footprint ""
		(layer "B.Cu")
		(at 420.776146 -48.922432 -90)
		(property "Reference" "R1T8"
			(at 0 0 90)
			(layer "B.SilkS")
			(hide yes)
			(effects
				(font
					(size 1.27 1.27)
				)
				(justify mirror)
			)
		)
		(property "Value" ""
			(at 0 0 90)
			(layer "B.Fab")
			(effects
				(font
					(size 1.27 1.27)
				)
				(justify mirror)
			)
		)
		(duplicate_pad_numbers_are_jumpers no)
		(fp_poly
			(pts
				(xy 0.2794 -0.1016) (xy -0.2794 -0.1016) (xy -0.2794 0.9906) (xy 0.2794 0.9906)
			)
			(stroke
				(width 0)
				(type default)
			)
			(fill no)
			(layer "B.CrtYd")
		)
		(fp_line
			(start -0.2794 0.9906)
			(end -0.2794 -0.1016)
			(stroke
				(width 0.1)
				(type default)
			)
			(layer "B.Fab")
		)
		(fp_line
			(start 0.2794 0.9906)
			(end -0.2794 0.9906)
			(stroke
				(width 0.1)
				(type default)
			)
			(layer "B.Fab")
		)
		(fp_line
			(start -0.2794 -0.1016)
			(end 0.2794 -0.1016)
			(stroke
				(width 0.1)
				(type default)
			)
			(layer "B.Fab")
		)
		(fp_line
			(start 0.2794 -0.1016)
			(end 0.2794 0.9906)
			(stroke
				(width 0.1)
				(type default)
			)
			(layer "B.Fab")
		)
		(pad "1" smd rect
			(at 0 0 90)
			(size 0.508 0.508)
			(layers "B.Cu" "B.Mask" "B.Paste")
			(net "SMB_SLOTX24_STBY_LVC3_SDA_R")
		)
		(pad "2" smd rect
			(at 0 0.889 90)
			(size 0.508 0.508)
			(layers "B.Cu" "B.Mask" "B.Paste")
			(net "SMB_SLOTX24_BMC_STBY_LVC3_SDA")
		)
		(zone
			(layer "B.Cu")
			(hatch none 0.5)
			(connect_pads
				(clearance 0)
			)
			(min_thickness 0.25)
			(keepout
				(tracks not_allowed)
				(vias allowed)
				(pads allowed)
				(copperpour not_allowed)
				(footprints allowed)
			)
			(placement
				(enabled no)
				(sheetname "")
			)
			(fill
				(thermal_gap 0.5)
				(thermal_bridge_width 0.5)
				(island_removal_mode 0)
			)
			(polygon
				(pts
					(xy 420.141146 -48.668432) (xy 420.141146 -49.176432) (xy 420.522146 -49.176432) (xy 420.522146 -48.668432)
				)
			)
		)
		(zone
			(layer "B.Cu")
			(hatch none 0.5)
			(connect_pads
				(clearance 0)
			)
			(min_thickness 0.25)
			(keepout
				(tracks allowed)
				(vias not_allowed)
				(pads allowed)
				(copperpour not_allowed)
				(footprints allowed)
			)
			(placement
				(enabled no)
				(sheetname "")
			)
			(fill
				(thermal_gap 0.5)
				(thermal_bridge_width 0.5)
				(island_removal_mode 0)
			)
			(polygon
				(pts
					(xy 420.522146 -48.668432) (xy 420.522146 -49.176432) (xy 420.141146 -49.176432) (xy 420.141146 -48.668432)
				)
			)
		)
	)
	(footprint ""
		(layer "B.Cu")
		(at 361.826556 -122.510042 -90)
		(property "Reference" "R778"
			(at 0.8382 -0.67818 270)
			(unlocked yes)
			(layer "B.SilkS")
			(effects
				(font
					(size 0.4064 0.254)
					(thickness 0.1524)
				)
				(justify left mirror)
			)
		)
		(property "Value" ""
			(at 0 0 90)
			(layer "B.Fab")
			(effects
				(font
					(size 1.27 1.27)
				)
				(justify mirror)
			)
		)
		(duplicate_pad_numbers_are_jumpers no)
		(fp_poly
			(pts
				(xy 0.2794 -0.1016) (xy -0.2794 -0.1016) (xy -0.2794 0.9906) (xy 0.2794 0.9906)
			)
			(stroke
				(width 0)
				(type default)
			)
			(fill no)
			(layer "B.CrtYd")
		)
		(fp_line
			(start -0.2794 0.9906)
			(end -0.2794 -0.1016)
			(stroke
				(width 0.1)
				(type default)
			)
			(layer "B.Fab")
		)
		(fp_line
			(start 0.2794 0.9906)
			(end -0.2794 0.9906)
			(stroke
				(width 0.1)
				(type default)
			)
			(layer "B.Fab")
		)
		(fp_line
			(start -0.2794 -0.1016)
			(end 0.2794 -0.1016)
			(stroke
				(width 0.1)
				(type default)
			)
			(layer "B.Fab")
		)
		(fp_line
			(start 0.2794 -0.1016)
			(end 0.2794 0.9906)
			(stroke
				(width 0.1)
				(type default)
			)
			(layer "B.Fab")
		)
		(pad "1" smd rect
			(at 0 0 90)
			(size 0.508 0.508)
			(layers "B.Cu" "B.Mask" "B.Paste")
			(net "P3E_CPU0_PE1_PCH_RXN<11>")
		)
		(pad "2" smd rect
			(at 0 0.889 90)
			(size 0.508 0.508)
			(layers "B.Cu" "B.Mask" "B.Paste")
			(net "P3E_CPU0_PE1_PCH_CON_RXN<11>")
		)
		(zone
			(layer "B.Cu")
			(hatch none 0.5)
			(connect_pads
				(clearance 0)
			)
			(min_thickness 0.25)
			(keepout
				(tracks not_allowed)
				(vias allowed)
				(pads allowed)
				(copperpour not_allowed)
				(footprints allowed)
			)
			(placement
				(enabled no)
				(sheetname "")
			)
			(fill
				(thermal_gap 0.5)
				(thermal_bridge_width 0.5)
				(island_removal_mode 0)
			)
			(polygon
				(pts
					(xy 361.191556 -122.256042) (xy 361.191556 -122.764042) (xy 361.572556 -122.764042) (xy 361.572556 -122.256042)
				)
			)
		)
		(zone
			(layer "B.Cu")
			(hatch none 0.5)
			(connect_pads
				(clearance 0)
			)
			(min_thickness 0.25)
			(keepout
				(tracks allowed)
				(vias not_allowed)
				(pads allowed)
				(copperpour not_allowed)
				(footprints allowed)
			)
			(placement
				(enabled no)
				(sheetname "")
			)
			(fill
				(thermal_gap 0.5)
				(thermal_bridge_width 0.5)
				(island_removal_mode 0)
			)
			(polygon
				(pts
					(xy 361.572556 -122.256042) (xy 361.572556 -122.764042) (xy 361.191556 -122.764042) (xy 361.191556 -122.256042)
				)
			)
		)
	)
	(footprint ""
		(layer "B.Cu")
		(at 373.498618 -89.78011)
		(property "Reference" "C7C19"
			(at 0 0 0)
			(layer "B.SilkS")
			(hide yes)
			(effects
				(font
					(size 1.27 1.27)
				)
				(justify mirror)
			)
		)
		(property "Value" ""
			(at 0 0 0)
			(layer "B.Fab")
			(effects
				(font
					(size 1.27 1.27)
				)
				(justify mirror)
			)
		)
		(duplicate_pad_numbers_are_jumpers no)
		(fp_poly
			(pts
				(xy -0.3048 -0.1016) (xy -0.3048 0.9906) (xy 0.3048 0.9906) (xy 0.3048 -0.1016)
			)
			(stroke
				(width 0)
				(type default)
			)
			(fill no)
			(layer "B.CrtYd")
		)
		(fp_line
			(start -0.3048 -0.1016)
			(end 0.3048 -0.1016)
			(stroke
				(width 0.1)
				(type default)
			)
			(layer "B.Fab")
		)
		(fp_line
			(start -0.3048 0.9906)
			(end -0.3048 -0.1016)
			(stroke
				(width 0.1)
				(type default)
			)
			(layer "B.Fab")
		)
		(fp_line
			(start 0.3048 -0.1016)
			(end 0.3048 0.9906)
			(stroke
				(width 0.1)
				(type default)
			)
			(layer "B.Fab")
		)
		(fp_line
			(start 0.3048 0.9906)
			(end -0.3048 0.9906)
			(stroke
				(width 0.1)
				(type default)
			)
			(layer "B.Fab")
		)
		(pad "1" smd rect
			(at 0 0 180)
			(size 0.508 0.508)
			(layers "B.Cu" "B.Mask" "B.Paste")
			(net "RST_RTCRST_N")
		)
		(pad "2" smd rect
			(at 0 0.889 180)
			(size 0.508 0.508)
			(layers "B.Cu" "B.Mask" "B.Paste")
			(net "GND")
		)
		(zone
			(layer "B.Cu")
			(hatch none 0.5)
			(connect_pads
				(clearance 0)
			)
			(min_thickness 0.25)
			(keepout
				(tracks allowed)
				(vias not_allowed)
				(pads allowed)
				(copperpour not_allowed)
				(footprints allowed)
			)
			(placement
				(enabled no)
				(sheetname "")
			)
			(fill
				(thermal_gap 0.5)
				(thermal_bridge_width 0.5)
				(island_removal_mode 0)
			)
			(polygon
				(pts
					(xy 373.752618 -89.52611) (xy 373.244618 -89.52611) (xy 373.244618 -89.14511) (xy 373.752618 -89.14511)
				)
			)
		)
		(zone
			(layer "B.Cu")
			(hatch none 0.5)
			(connect_pads
				(clearance 0)
			)
			(min_thickness 0.25)
			(keepout
				(tracks not_allowed)
				(vias allowed)
				(pads allowed)
				(copperpour not_allowed)
				(footprints allowed)
			)
			(placement
				(enabled no)
				(sheetname "")
			)
			(fill
				(thermal_gap 0.5)
				(thermal_bridge_width 0.5)
				(island_removal_mode 0)
			)
			(polygon
				(pts
					(xy 373.752618 -89.14511) (xy 373.244618 -89.14511) (xy 373.244618 -89.52611) (xy 373.752618 -89.52611)
				)
			)
		)
	)
)
